(kicad_pcb
	(version 20241229)
	(generator "pcbnew")
	(generator_version "9.0")
	(general
		(thickness 1.294)
		(legacy_teardrops no)
	)
	(paper "A3")
	(title_block
		(title "Kintex 410T devboard")
		(date "2024-04-03")
		(rev "1.1.2")
		(comment 9 "footprints 713-718 of 975")
	)
	(layers
		(0 "F.Cu" mixed)
		(4 "In1.Cu" power)
		(6 "In2.Cu" power)
		(8 "In3.Cu" mixed)
		(10 "In4.Cu" power)
		(12 "In5.Cu" mixed)
		(14 "In6.Cu" power)
		(16 "In7.Cu" mixed)
		(18 "In8.Cu" power)
		(2 "B.Cu" mixed)
		(9 "F.Adhes" user "F.Adhesive")
		(11 "B.Adhes" user "B.Adhesive")
		(13 "F.Paste" user)
		(15 "B.Paste" user)
		(5 "F.SilkS" user "F.Silkscreen")
		(7 "B.SilkS" user "B.Silkscreen")
		(1 "F.Mask" user)
		(3 "B.Mask" user)
		(17 "Dwgs.User" user "User.Drawings")
		(19 "Cmts.User" user "User.Comments")
		(21 "Eco1.User" user "User.Eco1")
		(23 "Eco2.User" user "User.Eco2")
		(25 "Edge.Cuts" user)
		(27 "Margin" user)
		(31 "F.CrtYd" user "F.Courtyard")
		(29 "B.CrtYd" user "B.Courtyard")
		(35 "F.Fab" user)
		(33 "B.Fab" user)
	)
	(footprint "antmicro-footprints:R_0402_1005Metric"
		(layer "B.Cu")
		(at 249.301 141.25 -90)
		(descr "Resistor SMD 0402")
		(tags "resistor SMD 0402")
		(property "Reference" "R88"
			(at 0.75 -0.399 90)
			(layer "B.SilkS")
			(effects
				(font
					(size 0.7 0.7)
					(thickness 0.15)
				)
				(justify left bottom mirror)
			)
		)
		(property "Value" "R_10k_0402"
			(at 0 -1.4 90)
			(layer "B.Fab")
			(effects
				(font
					(size 0.7 0.7)
					(thickness 0.15)
				)
				(justify left bottom mirror)
			)
		)
		(property "Description" "SMD Chip Resistor, 10 kohm, ± 1%, 62.5 mW, 0402 [1005 Metric], Thick Film, General Purpose"
			(at 0 0 270)
			(layer "F.Fab")
			(hide yes)
			(effects
				(font
					(size 1.27 1.27)
					(thickness 0.15)
				)
			)
		)
		(property "Author" "Antmicro"
			(at 108.051 390.551 0)
			(layer "B.Fab")
			(hide yes)
			(effects
				(font
					(size 1 1)
					(thickness 0.15)
				)
				(justify mirror)
			)
		)
		(property "License" "Apache-2.0"
			(at 108.051 390.551 0)
			(layer "B.Fab")
			(hide yes)
			(effects
				(font
					(size 1 1)
					(thickness 0.15)
				)
				(justify mirror)
			)
		)
		(property "MPN" "CR0402-FX-1002GLF"
			(at 108.051 390.551 0)
			(layer "B.Fab")
			(hide yes)
			(effects
				(font
					(size 1 1)
					(thickness 0.15)
				)
				(justify mirror)
			)
		)
		(property "Manufacturer" "Bourns"
			(at 108.051 390.551 0)
			(layer "B.Fab")
			(hide yes)
			(effects
				(font
					(size 1 1)
					(thickness 0.15)
				)
				(justify mirror)
			)
		)
		(property "Tolerance" "1%"
			(at 108.051 390.551 0)
			(layer "B.Fab")
			(hide yes)
			(effects
				(font
					(size 1 1)
					(thickness 0.15)
				)
				(justify mirror)
			)
		)
		(property "Val" "10k"
			(at 108.051 390.551 0)
			(layer "B.Fab")
			(hide yes)
			(effects
				(font
					(size 1 1)
					(thickness 0.15)
				)
				(justify mirror)
			)
		)
		(sheetname "SPI Flash + SD Card")
		(sheetfile "spi-flash.kicad_sch")
		(attr smd)
		(fp_rect
			(start -0.925 0.47)
			(end 0.925 -0.47)
			(stroke
				(width 0.05)
				(type default)
			)
			(fill no)
			(layer "B.CrtYd")
		)
		(fp_rect
			(start -0.5 0.25)
			(end 0.5 -0.25)
			(stroke
				(width 0.15)
				(type solid)
			)
			(fill no)
			(layer "B.Fab")
		)
		(pad "1" smd roundrect
			(at -0.48 0 270)
			(size 0.59 0.64)
			(layers "B.Cu" "B.Mask" "B.Paste")
			(roundrect_rratio 0.25)
			(net 393 "/FPGA Bank 33 & 34/SD_CARD.CMD")
			(pintype "passive")
		)
		(pad "2" smd roundrect
			(at 0.48 0 270)
			(size 0.59 0.64)
			(layers "B.Cu" "B.Mask" "B.Paste")
			(roundrect_rratio 0.25)
			(net 24 "+3V3")
			(pintype "passive")
		)
	)
	(footprint "antmicro-footprints:C_0402_1005Metric"
		(layer "B.Cu")
		(at 196.75 128.775 180)
		(descr "Capacitor SMD 0402")
		(tags "capacitor SMD 0402")
		(property "Reference" "C138"
			(at -25.45 28.75 0)
			(layer "B.SilkS")
			(effects
				(font
					(size 0.7 0.7)
					(thickness 0.15)
				)
				(justify left bottom mirror)
			)
		)
		(property "Value" "C_100n_0402"
			(at 0 -1.169 0)
			(layer "B.Fab")
			(effects
				(font
					(size 0.7 0.7)
					(thickness 0.15)
				)
				(justify left bottom mirror)
			)
		)
		(property "Description" "SMD Multilayer Ceramic Capacitor, 0.1 µF, 50 V, 0402 [1005 Metric], ± 10%, X5R, GRM Series"
			(at 0 0 180)
			(layer "F.Fab")
			(hide yes)
			(effects
				(font
					(size 1.27 1.27)
					(thickness 0.15)
				)
			)
		)
		(property "Author" "Antmicro"
			(at 393.5 257.55 0)
			(layer "B.Fab")
			(hide yes)
			(effects
				(font
					(size 1 1)
					(thickness 0.15)
				)
				(justify mirror)
			)
		)
		(property "Dielectric" "X5R"
			(at 393.5 257.55 0)
			(layer "B.Fab")
			(hide yes)
			(effects
				(font
					(size 1 1)
					(thickness 0.15)
				)
				(justify mirror)
			)
		)
		(property "License" "Apache-2.0"
			(at 393.5 257.55 0)
			(layer "B.Fab")
			(hide yes)
			(effects
				(font
					(size 1 1)
					(thickness 0.15)
				)
				(justify mirror)
			)
		)
		(property "MPN" "GRM155R61H104KE14D"
			(at 393.5 257.55 0)
			(layer "B.Fab")
			(hide yes)
			(effects
				(font
					(size 1 1)
					(thickness 0.15)
				)
				(justify mirror)
			)
		)
		(property "Manufacturer" "Murata"
			(at 393.5 257.55 0)
			(layer "B.Fab")
			(hide yes)
			(effects
				(font
					(size 1 1)
					(thickness 0.15)
				)
				(justify mirror)
			)
		)
		(property "Val" "100n"
			(at 393.5 257.55 0)
			(layer "B.Fab")
			(hide yes)
			(effects
				(font
					(size 1 1)
					(thickness 0.15)
				)
				(justify mirror)
			)
		)
		(property "Voltage" "50V"
			(at 393.5 257.55 0)
			(layer "B.Fab")
			(hide yes)
			(effects
				(font
					(size 1 1)
					(thickness 0.15)
				)
				(justify mirror)
			)
		)
		(sheetname "FPGA supply")
		(sheetfile "fpga-supply.kicad_sch")
		(attr smd)
		(fp_rect
			(start -0.925 0.47)
			(end 0.925 -0.47)
			(stroke
				(width 0.05)
				(type default)
			)
			(fill no)
			(layer "B.CrtYd")
		)
		(fp_line
			(start 0.504 0.25)
			(end 0.504 -0.248)
			(stroke
				(width 0.15)
				(type solid)
			)
			(layer "B.Fab")
		)
		(fp_line
			(start 0.504 -0.248)
			(end -0.494 -0.248)
			(stroke
				(width 0.15)
				(type solid)
			)
			(layer "B.Fab")
		)
		(fp_line
			(start -0.494 0.25)
			(end 0.504 0.25)
			(stroke
				(width 0.15)
				(type solid)
			)
			(layer "B.Fab")
		)
		(fp_line
			(start -0.494 -0.248)
			(end -0.494 0.25)
			(stroke
				(width 0.15)
				(type solid)
			)
			(layer "B.Fab")
		)
		(pad "1" smd roundrect
			(at -0.48 0 180)
			(size 0.59 0.64)
			(layers "B.Cu" "B.Mask" "B.Paste")
			(roundrect_rratio 0.25)
			(net 1 "GND")
			(pintype "passive")
		)
		(pad "2" smd roundrect
			(at 0.48 0 180)
			(size 0.59 0.64)
			(layers "B.Cu" "B.Mask" "B.Paste")
			(roundrect_rratio 0.25)
			(net 650 "+1V0")
			(pintype "passive")
		)
	)
	(footprint "antmicro-footprints:C_0402_1005Metric"
		(layer "B.Cu")
		(at 210.5 133 -90)
		(descr "Capacitor SMD 0402")
		(tags "capacitor SMD 0402")
		(property "Reference" "C25"
			(at -0.95 -1.2 90)
			(layer "B.SilkS")
			(effects
				(font
					(size 0.7 0.7)
					(thickness 0.15)
				)
				(justify left bottom mirror)
			)
		)
		(property "Value" "C_100n_0402"
			(at 0 -1.169 90)
			(layer "B.Fab")
			(effects
				(font
					(size 0.7 0.7)
					(thickness 0.15)
				)
				(justify left bottom mirror)
			)
		)
		(property "Description" "SMD Multilayer Ceramic Capacitor, 0.1 µF, 50 V, 0402 [1005 Metric], ± 10%, X5R, GRM Series"
			(at 0 0 270)
			(layer "F.Fab")
			(hide yes)
			(effects
				(font
					(size 1.27 1.27)
					(thickness 0.15)
				)
			)
		)
		(property "Author" "Antmicro"
			(at 77.5 343.5 0)
			(layer "B.Fab")
			(hide yes)
			(effects
				(font
					(size 1 1)
					(thickness 0.15)
				)
				(justify mirror)
			)
		)
		(property "Dielectric" "X5R"
			(at 77.5 343.5 0)
			(layer "B.Fab")
			(hide yes)
			(effects
				(font
					(size 1 1)
					(thickness 0.15)
				)
				(justify mirror)
			)
		)
		(property "License" "Apache-2.0"
			(at 77.5 343.5 0)
			(layer "B.Fab")
			(hide yes)
			(effects
				(font
					(size 1 1)
					(thickness 0.15)
				)
				(justify mirror)
			)
		)
		(property "MPN" "GRM155R61H104KE14D"
			(at 77.5 343.5 0)
			(layer "B.Fab")
			(hide yes)
			(effects
				(font
					(size 1 1)
					(thickness 0.15)
				)
				(justify mirror)
			)
		)
		(property "Manufacturer" "Murata"
			(at 77.5 343.5 0)
			(layer "B.Fab")
			(hide yes)
			(effects
				(font
					(size 1 1)
					(thickness 0.15)
				)
				(justify mirror)
			)
		)
		(property "Val" "100n"
			(at 77.5 343.5 0)
			(layer "B.Fab")
			(hide yes)
			(effects
				(font
					(size 1 1)
					(thickness 0.15)
				)
				(justify mirror)
			)
		)
		(property "Voltage" "50V"
			(at 77.5 343.5 0)
			(layer "B.Fab")
			(hide yes)
			(effects
				(font
					(size 1 1)
					(thickness 0.15)
				)
				(justify mirror)
			)
		)
		(sheetname "FPGA Bank 14 & 15")
		(sheetfile "fpga-bank-14-15.kicad_sch")
		(attr smd)
		(fp_rect
			(start -0.925 0.47)
			(end 0.925 -0.47)
			(stroke
				(width 0.05)
				(type default)
			)
			(fill no)
			(layer "B.CrtYd")
		)
		(fp_line
			(start -0.494 0.25)
			(end 0.504 0.25)
			(stroke
				(width 0.15)
				(type solid)
			)
			(layer "B.Fab")
		)
		(fp_line
			(start 0.504 0.25)
			(end 0.504 -0.248)
			(stroke
				(width 0.15)
				(type solid)
			)
			(layer "B.Fab")
		)
		(fp_line
			(start -0.494 -0.248)
			(end -0.494 0.25)
			(stroke
				(width 0.15)
				(type solid)
			)
			(layer "B.Fab")
		)
		(fp_line
			(start 0.504 -0.248)
			(end -0.494 -0.248)
			(stroke
				(width 0.15)
				(type solid)
			)
			(layer "B.Fab")
		)
		(pad "1" smd roundrect
			(at -0.48 0 270)
			(size 0.59 0.64)
			(layers "B.Cu" "B.Mask" "B.Paste")
			(roundrect_rratio 0.25)
			(net 1 "GND")
			(pintype "passive")
		)
		(pad "2" smd roundrect
			(at 0.48 0 270)
			(size 0.59 0.64)
			(layers "B.Cu" "B.Mask" "B.Paste")
			(roundrect_rratio 0.25)
			(net 24 "+3V3")
			(pintype "passive")
		)
	)
	(footprint "antmicro-footprints:R_0402_1005Metric"
		(layer "B.Cu")
		(at 165.685001 119.335001)
		(descr "Resistor SMD 0402")
		(tags "resistor SMD 0402")
		(property "Reference" "R268"
			(at -0.810001 0.439999 180)
			(layer "B.SilkS")
			(effects
				(font
					(size 0.7 0.7)
					(thickness 0.15)
				)
				(justify left bottom mirror)
			)
		)
		(property "Value" "R_4k7_0402"
			(at 0 -1.4 180)
			(layer "B.Fab")
			(effects
				(font
					(size 0.7 0.7)
					(thickness 0.15)
				)
				(justify left bottom mirror)
			)
		)
		(property "Description" "SMD Chip Resistor, 4.7 kohm, ± 1%, 62.5 mW, 0402 [1005 Metric], Thick Film, General Purpose"
			(at 0 0 0)
			(layer "F.Fab")
			(hide yes)
			(effects
				(font
					(size 1.27 1.27)
					(thickness 0.15)
				)
			)
		)
		(property "Author" "Antmicro"
			(at 0 0 0)
			(layer "B.Fab")
			(hide yes)
			(effects
				(font
					(size 1 1)
					(thickness 0.15)
				)
				(justify mirror)
			)
		)
		(property "License" "Apache-2.0"
			(at 0 0 0)
			(layer "B.Fab")
			(hide yes)
			(effects
				(font
					(size 1 1)
					(thickness 0.15)
				)
				(justify mirror)
			)
		)
		(property "MPN" "CR0402-FX-4701GLF"
			(at 0 0 0)
			(layer "B.Fab")
			(hide yes)
			(effects
				(font
					(size 1 1)
					(thickness 0.15)
				)
				(justify mirror)
			)
		)
		(property "Manufacturer" "Bourns"
			(at 0 0 0)
			(layer "B.Fab")
			(hide yes)
			(effects
				(font
					(size 1 1)
					(thickness 0.15)
				)
				(justify mirror)
			)
		)
		(property "Tolerance" "1%"
			(at 0 0 0)
			(layer "B.Fab")
			(hide yes)
			(effects
				(font
					(size 1 1)
					(thickness 0.15)
				)
				(justify mirror)
			)
		)
		(property "Val" "4k7"
			(at 0 0 0)
			(layer "B.Fab")
			(hide yes)
			(effects
				(font
					(size 1 1)
					(thickness 0.15)
				)
				(justify mirror)
			)
		)
		(sheetname "FMC+ HSPC")
		(sheetfile "fmc-hspc.kicad_sch")
		(attr smd)
		(fp_rect
			(start -0.925 0.47)
			(end 0.925 -0.47)
			(stroke
				(width 0.05)
				(type default)
			)
			(fill no)
			(layer "B.CrtYd")
		)
		(fp_rect
			(start -0.5 0.25)
			(end 0.5 -0.25)
			(stroke
				(width 0.15)
				(type solid)
			)
			(fill no)
			(layer "B.Fab")
		)
		(pad "1" smd roundrect
			(at -0.48 0)
			(size 0.59 0.64)
			(layers "B.Cu" "B.Mask" "B.Paste")
			(roundrect_rratio 0.25)
			(net 380 "FMC.SDA_3V3")
			(pintype "passive")
		)
		(pad "2" smd roundrect
			(at 0.48 0)
			(size 0.59 0.64)
			(layers "B.Cu" "B.Mask" "B.Paste")
			(roundrect_rratio 0.25)
			(net 24 "+3V3")
			(pintype "passive")
		)
	)
	(footprint "antmicro-footprints:C_0402_1005Metric"
		(layer "B.Cu")
		(at 214 143.5 180)
		(descr "Capacitor SMD 0402")
		(tags "capacitor SMD 0402")
		(property "Reference" "C18"
			(at -1.125 0.45 0)
			(layer "B.SilkS")
			(effects
				(font
					(size 0.7 0.7)
					(thickness 0.15)
				)
				(justify left bottom mirror)
			)
		)
		(property "Value" "C_100n_0402"
			(at 0 -1.169 0)
			(layer "B.Fab")
			(effects
				(font
					(size 0.7 0.7)
					(thickness 0.15)
				)
				(justify left bottom mirror)
			)
		)
		(property "Description" "SMD Multilayer Ceramic Capacitor, 0.1 µF, 50 V, 0402 [1005 Metric], ± 10%, X5R, GRM Series"
			(at 0 0 180)
			(layer "F.Fab")
			(hide yes)
			(effects
				(font
					(size 1.27 1.27)
					(thickness 0.15)
				)
			)
		)
		(property "Author" "Antmicro"
			(at 428 287 0)
			(layer "B.Fab")
			(hide yes)
			(effects
				(font
					(size 1 1)
					(thickness 0.15)
				)
				(justify mirror)
			)
		)
		(property "Dielectric" "X5R"
			(at 428 287 0)
			(layer "B.Fab")
			(hide yes)
			(effects
				(font
					(size 1 1)
					(thickness 0.15)
				)
				(justify mirror)
			)
		)
		(property "License" "Apache-2.0"
			(at 428 287 0)
			(layer "B.Fab")
			(hide yes)
			(effects
				(font
					(size 1 1)
					(thickness 0.15)
				)
				(justify mirror)
			)
		)
		(property "MPN" "GRM155R61H104KE14D"
			(at 428 287 0)
			(layer "B.Fab")
			(hide yes)
			(effects
				(font
					(size 1 1)
					(thickness 0.15)
				)
				(justify mirror)
			)
		)
		(property "Manufacturer" "Murata"
			(at 428 287 0)
			(layer "B.Fab")
			(hide yes)
			(effects
				(font
					(size 1 1)
					(thickness 0.15)
				)
				(justify mirror)
			)
		)
		(property "Val" "100n"
			(at 428 287 0)
			(layer "B.Fab")
			(hide yes)
			(effects
				(font
					(size 1 1)
					(thickness 0.15)
				)
				(justify mirror)
			)
		)
		(property "Voltage" "50V"
			(at 428 287 0)
			(layer "B.Fab")
			(hide yes)
			(effects
				(font
					(size 1 1)
					(thickness 0.15)
				)
				(justify mirror)
			)
		)
		(sheetname "FPGA Bank 12 & 13")
		(sheetfile "fpga-bank-12-13.kicad_sch")
		(attr smd)
		(fp_rect
			(start -0.925 0.47)
			(end 0.925 -0.47)
			(stroke
				(width 0.05)
				(type default)
			)
			(fill no)
			(layer "B.CrtYd")
		)
		(fp_line
			(start 0.504 0.25)
			(end 0.504 -0.248)
			(stroke
				(width 0.15)
				(type solid)
			)
			(layer "B.Fab")
		)
		(fp_line
			(start 0.504 -0.248)
			(end -0.494 -0.248)
			(stroke
				(width 0.15)
				(type solid)
			)
			(layer "B.Fab")
		)
		(fp_line
			(start -0.494 0.25)
			(end 0.504 0.25)
			(stroke
				(width 0.15)
				(type solid)
			)
			(layer "B.Fab")
		)
		(fp_line
			(start -0.494 -0.248)
			(end -0.494 0.25)
			(stroke
				(width 0.15)
				(type solid)
			)
			(layer "B.Fab")
		)
		(pad "1" smd roundrect
			(at -0.48 0 180)
			(size 0.59 0.64)
			(layers "B.Cu" "B.Mask" "B.Paste")
			(roundrect_rratio 0.25)
			(net 1 "GND")
			(pintype "passive")
		)
		(pad "2" smd roundrect
			(at 0.48 0 180)
			(size 0.59 0.64)
			(layers "B.Cu" "B.Mask" "B.Paste")
			(roundrect_rratio 0.25)
			(net 24 "+3V3")
			(pintype "passive")
		)
	)
	(footprint "antmicro-footprints:NetTie-2_SMD_Pad0.127mm"
		(layer "B.Cu")
		(at 254.101 148.4 -90)
		(descr "Net tie, 2 pin, 0.127mm  SMD pads")
		(tags "net tie")
		(property "Reference" "NT11"
			(at -0.128 1.345 90)
			(layer "B.SilkS")
			(hide yes)
			(effects
				(font
					(size 0.7 0.7)
					(thickness 0.15)
				)
				(justify left bottom mirror)
			)
		)
		(property "Value" "Net-Tie_2"
			(at 0 -1.199 90)
			(layer "B.Fab")
			(effects
				(font
					(size 0.7 0.7)
					(thickness 0.15)
				)
				(justify left bottom mirror)
			)
		)
		(property "Description" "Net tie, 2 pins"
			(at 0 0 270)
			(layer "F.Fab")
			(hide yes)
			(effects
				(font
					(size 1.27 1.27)
					(thickness 0.15)
				)
			)
		)
		(property "Author" "Antmicro"
			(at 105.701 402.501 0)
			(layer "B.Fab")
			(hide yes)
			(effects
				(font
					(size 1 1)
					(thickness 0.15)
				)
				(justify mirror)
			)
		)
		(property "License" "Apache-2.0"
			(at 105.701 402.501 0)
			(layer "B.Fab")
			(hide yes)
			(effects
				(font
					(size 1 1)
					(thickness 0.15)
				)
				(justify mirror)
			)
		)
		(property "MPN" ""
			(at 105.701 402.501 0)
			(layer "B.Fab")
			(hide yes)
			(effects
				(font
					(size 1 1)
					(thickness 0.15)
				)
				(justify mirror)
			)
		)
		(property "Manufacturer" ""
			(at 105.701 402.501 0)
			(layer "B.Fab")
			(hide yes)
			(effects
				(font
					(size 1 1)
					(thickness 0.15)
				)
				(justify mirror)
			)
		)
		(sheetname "FPGA Bank 14 & 15")
		(sheetfile "fpga-bank-14-15.kicad_sch")
		(attr exclude_from_pos_files)
		(net_tie_pad_groups "1, 2")
		(fp_poly
			(pts
				(xy -0.0635 0.0635) (xy 0.0625 0.0635) (xy 0.0625 -0.0635) (xy -0.0635 -0.0635)
			)
			(stroke
				(width 0)
				(type solid)
			)
			(fill yes)
			(layer "B.Cu")
		)
		(pad "1" smd roundrect
			(at -0.127 0 90)
			(size 0.127 0.127)
			(layers "B.Cu")
			(roundrect_rratio 0.5)
			(chamfer_ratio 0)
			(chamfer top_left bottom_left)
			(net 1296 "/USB_SPI.SCK")
			(pinfunction "1")
			(pintype "passive")
		)
		(pad "2" smd roundrect
			(at 0.126 0 270)
			(size 0.127 0.127)
			(layers "B.Cu")
			(roundrect_rratio 0.5)
			(chamfer_ratio 0)
			(chamfer top_left bottom_left)
			(net 1323 "/SUP_MCU.SCLK0")
			(pinfunction "2")
			(pintype "passive")
		)
	)
)
